(kicad_pcb
	(version 20260206)
	(generator "pcbnew")
	(generator_version "10.0")
	(general
		(thickness 1.6)
		(legacy_teardrops no)
	)
	(paper "A4")
	(title_block
		(title "01162023_DA0F0TEBIF0_F0T_Expander_BD_F_brd_V02_OCP.brd")
		(comment 1 "Grand Teton / footprints 2671-2678 of 9728")
	)
	(layers
		(0 "F.Cu" signal "TOP")
		(4 "In1.Cu" signal "GND")
		(6 "In2.Cu" signal "VCC")
		(8 "In3.Cu" signal "VCC1")
		(10 "In4.Cu" signal "GND1")
		(12 "In5.Cu" signal "IN1")
		(14 "In6.Cu" signal "GND2")
		(16 "In7.Cu" signal "IN2")
		(18 "In8.Cu" signal "GND3")
		(20 "In9.Cu" signal "IN3")
		(22 "In10.Cu" signal "GND4")
		(24 "In11.Cu" signal "IN4")
		(26 "In12.Cu" signal "GND5")
		(28 "In13.Cu" signal "IN5")
		(30 "In14.Cu" signal "GND6")
		(32 "In15.Cu" signal "IN6")
		(34 "In16.Cu" signal "GND7")
		(2 "B.Cu" signal "BOTTOM")
		(9 "F.Adhes" user "F.Adhesive")
		(11 "B.Adhes" user "B.Adhesive")
		(13 "F.Paste" user "Package Geometry/Pastemask Top")
		(15 "B.Paste" user "Package Geometry/Pastemask Bottom")
		(5 "F.SilkS" user "Ref Des/Silkscreen Top")
		(7 "B.SilkS" user "Ref Des/Silkscreen Bottom")
		(1 "F.Mask" user "Board Geometry/Soldermask Top")
		(3 "B.Mask" user "Board Geometry/Soldermask Bottom")
		(17 "Dwgs.User" user "User.Drawings")
		(19 "Cmts.User" user "User.Comments")
		(21 "Eco1.User" user "User.Eco1")
		(23 "Eco2.User" user "User.Eco2")
		(25 "Edge.Cuts" user "Board Geometry/Outline")
		(27 "Margin" user)
		(31 "F.CrtYd" user "Package Geometry/Place Bound Top")
		(29 "B.CrtYd" user "Package Geometry/Place Bound Bottom")
		(35 "F.Fab" user "Ref Des/Assembly Top")
		(33 "B.Fab" user "Ref Des/Assembly Bottom")
	)
	(footprint ""
		(layer "F.Cu")
		(at 367.708434 -142.455392 180)
		(property "Reference" "R748"
			(at 0 0 180)
			(layer "F.SilkS")
			(hide yes)
			(effects
				(font
					(size 1.27 1.27)
				)
			)
		)
		(property "Value" ""
			(at 0 0 180)
			(layer "F.Fab")
			(effects
				(font
					(size 1.27 1.27)
				)
			)
		)
		(duplicate_pad_numbers_are_jumpers no)
		(fp_line
			(start 3.937508 1.8796)
			(end 3.937508 -1.8796)
			(stroke
				(width 0.1524)
				(type default)
			)
			(layer "F.SilkS")
		)
		(fp_line
			(start 3.937508 -1.8796)
			(end -3.937508 -1.8796)
			(stroke
				(width 0.1524)
				(type default)
			)
			(layer "F.SilkS")
		)
		(fp_line
			(start -3.937508 1.8796)
			(end 3.937508 1.8796)
			(stroke
				(width 0.1524)
				(type default)
			)
			(layer "F.SilkS")
		)
		(fp_line
			(start -3.937508 -1.8796)
			(end -3.937508 1.8796)
			(stroke
				(width 0.1524)
				(type default)
			)
			(layer "F.SilkS")
		)
		(fp_line
			(start 3.275076 1.674876)
			(end 3.275076 -1.674876)
			(stroke
				(width 0.1)
				(type default)
			)
			(layer "F.Fab")
		)
		(fp_line
			(start 3.275076 -1.674876)
			(end -3.275076 -1.674876)
			(stroke
				(width 0.1)
				(type default)
			)
			(layer "F.Fab")
		)
		(fp_line
			(start -3.275076 1.674876)
			(end 3.275076 1.674876)
			(stroke
				(width 0.1)
				(type default)
			)
			(layer "F.Fab")
		)
		(fp_line
			(start -3.275076 -1.674876)
			(end -3.275076 1.674876)
			(stroke
				(width 0.1)
				(type default)
			)
			(layer "F.Fab")
		)
		(pad "1" smd rect
			(at -2.350008 0 180)
			(size 2.921 3.5052)
			(layers "F.Cu" "F.Mask" "F.Paste")
			(net "P12V_NIC6")
		)
		(pad "2" smd rect
			(at 2.350008 0 180)
			(size 2.921 3.5052)
			(layers "F.Cu" "F.Mask" "F.Paste")
			(net "P12V_NIC6_R")
		)
	)
	(footprint ""
		(layer "F.Cu")
		(at 330.325222 -42.849038 180)
		(property "Reference" "R634"
			(at 0 0 180)
			(layer "F.SilkS")
			(hide yes)
			(effects
				(font
					(size 1.27 1.27)
				)
			)
		)
		(property "Value" ""
			(at 0 0 180)
			(layer "F.Fab")
			(effects
				(font
					(size 1.27 1.27)
				)
			)
		)
		(duplicate_pad_numbers_are_jumpers no)
		(fp_line
			(start 0.7874 0.4064)
			(end -0.7874 0.4064)
			(stroke
				(width 0.1524)
				(type default)
			)
			(layer "F.SilkS")
		)
		(fp_line
			(start 0.7874 -0.4064)
			(end 0.7874 0.4064)
			(stroke
				(width 0.1524)
				(type default)
			)
			(layer "F.SilkS")
		)
		(fp_line
			(start -0.7874 0.4064)
			(end -0.7874 -0.4064)
			(stroke
				(width 0.1524)
				(type default)
			)
			(layer "F.SilkS")
		)
		(fp_line
			(start -0.7874 -0.4064)
			(end 0.7874 -0.4064)
			(stroke
				(width 0.1524)
				(type default)
			)
			(layer "F.SilkS")
		)
		(fp_line
			(start 0.67945 0.3048)
			(end 0.120396 0.3048)
			(stroke
				(width 0.1)
				(type default)
			)
			(layer "F.Fab")
		)
		(fp_line
			(start 0.67945 -0.3048)
			(end 0.67945 0.3048)
			(stroke
				(width 0.1)
				(type default)
			)
			(layer "F.Fab")
		)
		(fp_line
			(start 0.12065 -0.2794)
			(end 0.12065 -0.3048)
			(stroke
				(width 0.1)
				(type default)
			)
			(layer "F.Fab")
		)
		(fp_line
			(start 0.12065 -0.3048)
			(end 0.67945 -0.3048)
			(stroke
				(width 0.1)
				(type default)
			)
			(layer "F.Fab")
		)
		(fp_line
			(start 0.120396 0.3048)
			(end 0.120396 0.2794)
			(stroke
				(width 0.1)
				(type default)
			)
			(layer "F.Fab")
		)
		(fp_line
			(start 0.120396 0.2794)
			(end -0.12065 0.2794)
			(stroke
				(width 0.1)
				(type default)
			)
			(layer "F.Fab")
		)
		(fp_line
			(start -0.12065 0.3048)
			(end -0.67945 0.3048)
			(stroke
				(width 0.1)
				(type default)
			)
			(layer "F.Fab")
		)
		(fp_line
			(start -0.12065 0.2794)
			(end -0.12065 0.3048)
			(stroke
				(width 0.1)
				(type default)
			)
			(layer "F.Fab")
		)
		(fp_line
			(start -0.12065 -0.2794)
			(end 0.12065 -0.2794)
			(stroke
				(width 0.1)
				(type default)
			)
			(layer "F.Fab")
		)
		(fp_line
			(start -0.12065 -0.305054)
			(end -0.12065 -0.2794)
			(stroke
				(width 0.1)
				(type default)
			)
			(layer "F.Fab")
		)
		(fp_line
			(start -0.67945 0.3048)
			(end -0.67945 -0.305054)
			(stroke
				(width 0.1)
				(type default)
			)
			(layer "F.Fab")
		)
		(fp_line
			(start -0.67945 -0.305054)
			(end -0.12065 -0.305054)
			(stroke
				(width 0.1)
				(type default)
			)
			(layer "F.Fab")
		)
		(pad "1" smd circle
			(at -0.40005 0 180)
			(size 0 0)
			(layers "F.Cu" "F.Mask" "F.Paste")
			(net "P12V_SSD11_R")
		)
		(pad "2" smd circle
			(at 0.40005 0 180)
			(size 0 0)
			(layers "F.Cu" "F.Mask" "F.Paste")
			(net "P12V_SSD11_VIN_P")
		)
	)
	(footprint ""
		(layer "F.Cu")
		(at 319.70218 -389.98779 180)
		(property "Reference" "R6774"
			(at 0 0 180)
			(layer "F.SilkS")
			(hide yes)
			(effects
				(font
					(size 1.27 1.27)
				)
			)
		)
		(property "Value" ""
			(at 0 0 180)
			(layer "F.Fab")
			(effects
				(font
					(size 1.27 1.27)
				)
			)
		)
		(duplicate_pad_numbers_are_jumpers no)
		(fp_line
			(start 0.7874 0.4064)
			(end -0.7874 0.4064)
			(stroke
				(width 0.1524)
				(type default)
			)
			(layer "F.SilkS")
		)
		(fp_line
			(start 0.7874 -0.4064)
			(end 0.7874 0.4064)
			(stroke
				(width 0.1524)
				(type default)
			)
			(layer "F.SilkS")
		)
		(fp_line
			(start -0.7874 0.4064)
			(end -0.7874 -0.4064)
			(stroke
				(width 0.1524)
				(type default)
			)
			(layer "F.SilkS")
		)
		(fp_line
			(start -0.7874 -0.4064)
			(end 0.7874 -0.4064)
			(stroke
				(width 0.1524)
				(type default)
			)
			(layer "F.SilkS")
		)
		(fp_line
			(start 0.67945 0.3048)
			(end 0.120396 0.3048)
			(stroke
				(width 0.1)
				(type default)
			)
			(layer "F.Fab")
		)
		(fp_line
			(start 0.67945 -0.3048)
			(end 0.67945 0.3048)
			(stroke
				(width 0.1)
				(type default)
			)
			(layer "F.Fab")
		)
		(fp_line
			(start 0.12065 -0.2794)
			(end 0.12065 -0.3048)
			(stroke
				(width 0.1)
				(type default)
			)
			(layer "F.Fab")
		)
		(fp_line
			(start 0.12065 -0.3048)
			(end 0.67945 -0.3048)
			(stroke
				(width 0.1)
				(type default)
			)
			(layer "F.Fab")
		)
		(fp_line
			(start 0.120396 0.3048)
			(end 0.120396 0.2794)
			(stroke
				(width 0.1)
				(type default)
			)
			(layer "F.Fab")
		)
		(fp_line
			(start 0.120396 0.2794)
			(end -0.12065 0.2794)
			(stroke
				(width 0.1)
				(type default)
			)
			(layer "F.Fab")
		)
		(fp_line
			(start -0.12065 0.3048)
			(end -0.67945 0.3048)
			(stroke
				(width 0.1)
				(type default)
			)
			(layer "F.Fab")
		)
		(fp_line
			(start -0.12065 0.2794)
			(end -0.12065 0.3048)
			(stroke
				(width 0.1)
				(type default)
			)
			(layer "F.Fab")
		)
		(fp_line
			(start -0.12065 -0.2794)
			(end 0.12065 -0.2794)
			(stroke
				(width 0.1)
				(type default)
			)
			(layer "F.Fab")
		)
		(fp_line
			(start -0.12065 -0.305054)
			(end -0.12065 -0.2794)
			(stroke
				(width 0.1)
				(type default)
			)
			(layer "F.Fab")
		)
		(fp_line
			(start -0.67945 0.3048)
			(end -0.67945 -0.305054)
			(stroke
				(width 0.1)
				(type default)
			)
			(layer "F.Fab")
		)
		(fp_line
			(start -0.67945 -0.305054)
			(end -0.12065 -0.305054)
			(stroke
				(width 0.1)
				(type default)
			)
			(layer "F.Fab")
		)
		(pad "1" smd circle
			(at -0.40005 0 180)
			(size 0 0)
			(layers "F.Cu" "F.Mask" "F.Paste")
			(net "PRSNT_GPU_A2_R_N")
		)
		(pad "2" smd circle
			(at 0.40005 0 180)
			(size 0 0)
			(layers "F.Cu" "F.Mask" "F.Paste")
			(net "PRSNT_GPU_A2_N")
		)
	)
	(footprint ""
		(layer "F.Cu")
		(at 110.49635 -79.822294 90)
		(property "Reference" "R1141"
			(at 0 0 90)
			(layer "F.SilkS")
			(hide yes)
			(effects
				(font
					(size 1.27 1.27)
				)
			)
		)
		(property "Value" ""
			(at 0 0 90)
			(layer "F.Fab")
			(effects
				(font
					(size 1.27 1.27)
				)
			)
		)
		(duplicate_pad_numbers_are_jumpers no)
		(fp_line
			(start 0.7874 0.4064)
			(end -0.7874 0.4064)
			(stroke
				(width 0.1524)
				(type default)
			)
			(layer "F.SilkS")
		)
		(fp_line
			(start -0.12065 -0.305054)
			(end -0.12065 -0.2794)
			(stroke
				(width 0.1)
				(type default)
			)
			(layer "F.Fab")
		)
		(fp_line
			(start -0.67945 -0.305054)
			(end -0.12065 -0.305054)
			(stroke
				(width 0.1)
				(type default)
			)
			(layer "F.Fab")
		)
		(fp_line
			(start 0.67945 -0.3048)
			(end 0.67945 0.3048)
			(stroke
				(width 0.1)
				(type default)
			)
			(layer "F.Fab")
		)
		(fp_line
			(start 0.12065 -0.3048)
			(end 0.67945 -0.3048)
			(stroke
				(width 0.1)
				(type default)
			)
			(layer "F.Fab")
		)
		(fp_line
			(start 0.12065 -0.2794)
			(end 0.12065 -0.3048)
			(stroke
				(width 0.1)
				(type default)
			)
			(layer "F.Fab")
		)
		(fp_line
			(start -0.12065 -0.2794)
			(end 0.12065 -0.2794)
			(stroke
				(width 0.1)
				(type default)
			)
			(layer "F.Fab")
		)
		(fp_line
			(start 0.120396 0.2794)
			(end -0.12065 0.2794)
			(stroke
				(width 0.1)
				(type default)
			)
			(layer "F.Fab")
		)
		(fp_line
			(start -0.12065 0.2794)
			(end -0.12065 0.3048)
			(stroke
				(width 0.1)
				(type default)
			)
			(layer "F.Fab")
		)
		(fp_line
			(start 0.67945 0.3048)
			(end 0.120396 0.3048)
			(stroke
				(width 0.1)
				(type default)
			)
			(layer "F.Fab")
		)
		(fp_line
			(start 0.120396 0.3048)
			(end 0.120396 0.2794)
			(stroke
				(width 0.1)
				(type default)
			)
			(layer "F.Fab")
		)
		(fp_line
			(start -0.12065 0.3048)
			(end -0.67945 0.3048)
			(stroke
				(width 0.1)
				(type default)
			)
			(layer "F.Fab")
		)
		(fp_line
			(start -0.67945 0.3048)
			(end -0.67945 -0.305054)
			(stroke
				(width 0.1)
				(type default)
			)
			(layer "F.Fab")
		)
		(pad "1" smd circle
			(at -0.40005 0 90)
			(size 0 0)
			(layers "F.Cu" "F.Mask" "F.Paste")
			(net "CLK_100M_DB800ZL_SSD2_R_DN")
		)
		(pad "2" smd circle
			(at 0.40005 0 90)
			(size 0 0)
			(layers "F.Cu" "F.Mask" "F.Paste")
			(net "CLK_100M_DB800ZL_SSD2_DN")
		)
	)
	(footprint ""
		(layer "F.Cu")
		(at 314.861448 -156.111194 180)
		(property "Reference" "C423"
			(at 0 0 180)
			(layer "F.SilkS")
			(hide yes)
			(effects
				(font
					(size 1.27 1.27)
				)
			)
		)
		(property "Value" ""
			(at 0 0 180)
			(layer "F.Fab")
			(effects
				(font
					(size 1.27 1.27)
				)
			)
		)
		(duplicate_pad_numbers_are_jumpers no)
		(fp_line
			(start 0.299974 0.150114)
			(end -0.299974 0.150114)
			(stroke
				(width 0.1)
				(type default)
			)
			(layer "F.Fab")
		)
		(fp_line
			(start 0.299974 -0.150114)
			(end 0.299974 0.150114)
			(stroke
				(width 0.1)
				(type default)
			)
			(layer "F.Fab")
		)
		(fp_line
			(start -0.299974 0.150114)
			(end -0.299974 -0.150114)
			(stroke
				(width 0.1)
				(type default)
			)
			(layer "F.Fab")
		)
		(fp_line
			(start -0.299974 -0.150114)
			(end 0.299974 -0.150114)
			(stroke
				(width 0.1)
				(type default)
			)
			(layer "F.Fab")
		)
		(pad "1" smd rect
			(at -0.2667 0 180)
			(size 0.3048 0.381)
			(layers "F.Cu" "F.Mask" "F.Paste")
			(net "P5E_PEX2_STN0_TX_DP<15>")
		)
		(pad "2" smd rect
			(at 0.2667 0 180)
			(size 0.3048 0.381)
			(layers "F.Cu" "F.Mask" "F.Paste")
			(net "P5E_PEX2_STN0_TX_C_DP<15>")
		)
	)
	(footprint ""
		(layer "F.Cu")
		(at 95.79229 -32.739584 180)
		(property "Reference" "C91"
			(at 0 0 180)
			(layer "F.SilkS")
			(hide yes)
			(effects
				(font
					(size 1.27 1.27)
				)
			)
		)
		(property "Value" ""
			(at 0 0 180)
			(layer "F.Fab")
			(effects
				(font
					(size 1.27 1.27)
				)
			)
		)
		(duplicate_pad_numbers_are_jumpers no)
		(fp_line
			(start 0.299974 0.150114)
			(end -0.299974 0.150114)
			(stroke
				(width 0.1)
				(type default)
			)
			(layer "F.Fab")
		)
		(fp_line
			(start 0.299974 -0.150114)
			(end 0.299974 0.150114)
			(stroke
				(width 0.1)
				(type default)
			)
			(layer "F.Fab")
		)
		(fp_line
			(start -0.299974 0.150114)
			(end -0.299974 -0.150114)
			(stroke
				(width 0.1)
				(type default)
			)
			(layer "F.Fab")
		)
		(fp_line
			(start -0.299974 -0.150114)
			(end 0.299974 -0.150114)
			(stroke
				(width 0.1)
				(type default)
			)
			(layer "F.Fab")
		)
		(pad "1" smd rect
			(at -0.2667 0 180)
			(size 0.3048 0.381)
			(layers "F.Cu" "F.Mask" "F.Paste")
			(net "P5E_PEX0_STN2_TX_DP<34>")
		)
		(pad "2" smd rect
			(at 0.2667 0 180)
			(size 0.3048 0.381)
			(layers "F.Cu" "F.Mask" "F.Paste")
			(net "P5E_PEX0_STN2_TX_C_DP<34>")
		)
	)
	(footprint ""
		(layer "F.Cu")
		(at 155.380436 -125.519942)
		(property "Reference" "C253"
			(at 0 0 0)
			(layer "F.SilkS")
			(hide yes)
			(effects
				(font
					(size 1.27 1.27)
				)
			)
		)
		(property "Value" ""
			(at 0 0 0)
			(layer "F.Fab")
			(effects
				(font
					(size 1.27 1.27)
				)
			)
		)
		(duplicate_pad_numbers_are_jumpers no)
		(fp_line
			(start -0.299974 -0.150114)
			(end 0.299974 -0.150114)
			(stroke
				(width 0.1)
				(type default)
			)
			(layer "F.Fab")
		)
		(fp_line
			(start -0.299974 0.150114)
			(end -0.299974 -0.150114)
			(stroke
				(width 0.1)
				(type default)
			)
			(layer "F.Fab")
		)
		(fp_line
			(start 0.299974 -0.150114)
			(end 0.299974 0.150114)
			(stroke
				(width 0.1)
				(type default)
			)
			(layer "F.Fab")
		)
		(fp_line
			(start 0.299974 0.150114)
			(end -0.299974 0.150114)
			(stroke
				(width 0.1)
				(type default)
			)
			(layer "F.Fab")
		)
		(pad "1" smd rect
			(at -0.2667 0)
			(size 0.3048 0.381)
			(layers "F.Cu" "F.Mask" "F.Paste")
			(net "P5E_PEX1_STN1_TX_DP<27>")
		)
		(pad "2" smd rect
			(at 0.2667 0)
			(size 0.3048 0.381)
			(layers "F.Cu" "F.Mask" "F.Paste")
			(net "P5E_PEX1_STN1_TX_C_DP<27>")
		)
	)
	(footprint ""
		(layer "F.Cu")
		(at 286.040068 -32.848042 90)
		(property "Reference" "PC955"
			(at 0 0 90)
			(layer "F.SilkS")
			(hide yes)
			(effects
				(font
					(size 1.27 1.27)
				)
			)
		)
		(property "Value" ""
			(at 0 0 90)
			(layer "F.Fab")
			(effects
				(font
					(size 1.27 1.27)
				)
			)
		)
		(duplicate_pad_numbers_are_jumpers no)
		(fp_line
			(start 0.7874 -0.4064)
			(end 0.7874 0.4064)
			(stroke
				(width 0.1524)
				(type default)
			)
			(layer "F.SilkS")
		)
		(fp_line
			(start -0.7874 -0.4064)
			(end 0.7874 -0.4064)
			(stroke
				(width 0.1524)
				(type default)
			)
			(layer "F.SilkS")
		)
		(fp_line
			(start 0.7874 0.4064)
			(end -0.7874 0.4064)
			(stroke
				(width 0.1524)
				(type default)
			)
			(layer "F.SilkS")
		)
		(fp_line
			(start -0.7874 0.4064)
			(end -0.7874 -0.4064)
			(stroke
				(width 0.1524)
				(type default)
			)
			(layer "F.SilkS")
		)
		(fp_line
			(start -0.12065 -0.305054)
			(end -0.12065 -0.2794)
			(stroke
				(width 0.1)
				(type default)
			)
			(layer "F.Fab")
		)
		(fp_line
			(start -0.67945 -0.305054)
			(end -0.12065 -0.305054)
			(stroke
				(width 0.1)
				(type default)
			)
			(layer "F.Fab")
		)
		(fp_line
			(start 0.67945 -0.3048)
			(end 0.67945 0.3048)
			(stroke
				(width 0.1)
				(type default)
			)
			(layer "F.Fab")
		)
		(fp_line
			(start 0.12065 -0.3048)
			(end 0.67945 -0.3048)
			(stroke
				(width 0.1)
				(type default)
			)
			(layer "F.Fab")
		)
		(fp_line
			(start 0.12065 -0.2794)
			(end 0.12065 -0.3048)
			(stroke
				(width 0.1)
				(type default)
			)
			(layer "F.Fab")
		)
		(fp_line
			(start -0.12065 -0.2794)
			(end 0.12065 -0.2794)
			(stroke
				(width 0.1)
				(type default)
			)
			(layer "F.Fab")
		)
		(fp_line
			(start 0.120396 0.2794)
			(end -0.12065 0.2794)
			(stroke
				(width 0.1)
				(type default)
			)
			(layer "F.Fab")
		)
		(fp_line
			(start -0.12065 0.2794)
			(end -0.12065 0.3048)
			(stroke
				(width 0.1)
				(type default)
			)
			(layer "F.Fab")
		)
		(fp_line
			(start 0.67945 0.3048)
			(end 0.120396 0.3048)
			(stroke
				(width 0.1)
				(type default)
			)
			(layer "F.Fab")
		)
		(fp_line
			(start 0.120396 0.3048)
			(end 0.120396 0.2794)
			(stroke
				(width 0.1)
				(type default)
			)
			(layer "F.Fab")
		)
		(fp_line
			(start -0.12065 0.3048)
			(end -0.67945 0.3048)
			(stroke
				(width 0.1)
				(type default)
			)
			(layer "F.Fab")
		)
		(fp_line
			(start -0.67945 0.3048)
			(end -0.67945 -0.305054)
			(stroke
				(width 0.1)
				(type default)
			)
			(layer "F.Fab")
		)
		(pad "1" smd circle
			(at -0.40005 0 90)
			(size 0 0)
			(layers "F.Cu" "F.Mask" "F.Paste")
			(net "P3V3_SSD10_CO_DV_DT")
		)
		(pad "2" smd circle
			(at 0.40005 0 90)
			(size 0 0)
			(layers "F.Cu" "F.Mask" "F.Paste")
			(net "GND")
		)
	)
)
